(kicad_pcb
	(version 20260206)
	(generator "pcbnew")
	(generator_version "10.0")
	(general
		(thickness 1.6)
		(legacy_teardrops no)
	)
	(paper "A4")
	(title_block
		(title "01162023_DA0F0TEBIF0_F0T_Expander_BD_F_brd_V02_OCP.brd")
		(comment 1 "Grand Teton / footprint 4451 of 9728 (PEX3), pads 117-233 of 2397")
	)
	(layers
		(0 "F.Cu" signal "TOP")
		(4 "In1.Cu" signal "GND")
		(6 "In2.Cu" signal "VCC")
		(8 "In3.Cu" signal "VCC1")
		(10 "In4.Cu" signal "GND1")
		(12 "In5.Cu" signal "IN1")
		(14 "In6.Cu" signal "GND2")
		(16 "In7.Cu" signal "IN2")
		(18 "In8.Cu" signal "GND3")
		(20 "In9.Cu" signal "IN3")
		(22 "In10.Cu" signal "GND4")
		(24 "In11.Cu" signal "IN4")
		(26 "In12.Cu" signal "GND5")
		(28 "In13.Cu" signal "IN5")
		(30 "In14.Cu" signal "GND6")
		(32 "In15.Cu" signal "IN6")
		(34 "In16.Cu" signal "GND7")
		(2 "B.Cu" signal "BOTTOM")
		(9 "F.Adhes" user "F.Adhesive")
		(11 "B.Adhes" user "B.Adhesive")
		(13 "F.Paste" user "Package Geometry/Pastemask Top")
		(15 "B.Paste" user "Package Geometry/Pastemask Bottom")
		(5 "F.SilkS" user "Ref Des/Silkscreen Top")
		(7 "B.SilkS" user "Ref Des/Silkscreen Bottom")
		(1 "F.Mask" user "Board Geometry/Soldermask Top")
		(3 "B.Mask" user "Board Geometry/Soldermask Bottom")
		(17 "Dwgs.User" user "User.Drawings")
		(19 "Cmts.User" user "User.Comments")
		(21 "Eco1.User" user "User.Eco1")
		(23 "Eco2.User" user "User.Eco2")
		(25 "Edge.Cuts" user "Board Geometry/Outline")
		(27 "Margin" user)
		(31 "F.CrtYd" user "Package Geometry/Place Bound Top")
		(29 "B.CrtYd" user "Package Geometry/Place Bound Bottom")
		(35 "F.Fab" user "Ref Des/Assembly Top")
		(33 "B.Fab" user "Ref Des/Assembly Bottom")
	)
	(footprint ""
		(layer "F.Cu")
		(at 407.949908 -295.89984)
		(property "Reference" "PEX3"
			(at -3.358642 35.5727 0)
			(unlocked yes)
			(layer "F.SilkS")
			(effects
				(font
					(size 2.032 1.524)
					(thickness 0.1524)
				)
				(justify left)
			)
		)
		(property "Value" ""
			(at 0 0 0)
			(layer "F.Fab")
			(effects
				(font
					(size 1.27 1.27)
				)
			)
		)
		(duplicate_pad_numbers_are_jumpers no)
		(pad "AB21" smd circle
			(at -3.800094 -2.84988)
			(size 0.4572 0.4572)
			(layers "F.Cu" "F.Mask" "F.Paste")
			(net "P0V8_SERDES_VDDA_PEX3")
		)
		(pad "AB22" smd circle
			(at -2.84988 -2.84988)
			(size 0.4572 0.4572)
			(layers "F.Cu" "F.Mask" "F.Paste")
			(net "P0V8_SERDES_VDDA_PEX3")
		)
		(pad "AB23" smd circle
			(at -1.89992 -2.84988)
			(size 0.4572 0.4572)
			(layers "F.Cu" "F.Mask" "F.Paste")
			(net "P0V8_SERDES_VDDA_PEX3")
		)
		(pad "AB24" smd circle
			(at -0.94996 -2.84988)
			(size 0.4572 0.4572)
			(layers "F.Cu" "F.Mask" "F.Paste")
			(net "P0V8_SERDES_VDDA_PEX3")
		)
		(pad "AB25" smd circle
			(at 0 -2.84988)
			(size 0.4572 0.4572)
			(layers "F.Cu" "F.Mask" "F.Paste")
			(net "P0V8_SERDES_VDDA_PEX3")
		)
		(pad "AB26" smd circle
			(at 0.94996 -2.84988)
			(size 0.4572 0.4572)
			(layers "F.Cu" "F.Mask" "F.Paste")
			(net "P0V8_SERDES_VDDA_PEX3")
		)
		(pad "AB27" smd circle
			(at 1.89992 -2.84988)
			(size 0.4572 0.4572)
			(layers "F.Cu" "F.Mask" "F.Paste")
			(net "P0V8_SERDES_VDDA_PEX3")
		)
		(pad "AB28" smd circle
			(at 2.84988 -2.84988)
			(size 0.4572 0.4572)
			(layers "F.Cu" "F.Mask" "F.Paste")
			(net "P0V8_SERDES_VDDA_PEX3")
		)
		(pad "AB29" smd circle
			(at 3.800094 -2.84988)
			(size 0.4572 0.4572)
			(layers "F.Cu" "F.Mask" "F.Paste")
			(net "P0V8_SERDES_VDDA_PEX3")
		)
		(pad "AB30" smd circle
			(at 4.750054 -2.84988)
			(size 0.4572 0.4572)
			(layers "F.Cu" "F.Mask" "F.Paste")
			(net "P0V8_SERDES_VDDA_PEX3")
		)
		(pad "AB31" smd circle
			(at 5.700014 -2.84988)
			(size 0.4572 0.4572)
			(layers "F.Cu" "F.Mask" "F.Paste")
			(net "P0V8_SERDES_VDDA_PEX3")
		)
		(pad "AB32" smd circle
			(at 6.649974 -2.84988)
			(size 0.4572 0.4572)
			(layers "F.Cu" "F.Mask" "F.Paste")
			(net "P0V8_SERDES_VDDA_PEX3")
		)
		(pad "AB33" smd circle
			(at 7.599934 -2.84988)
			(size 0.4572 0.4572)
			(layers "F.Cu" "F.Mask" "F.Paste")
			(net "P0V8_SERDES_VDDA_PEX3")
		)
		(pad "AB34" smd circle
			(at 8.549894 -2.84988)
			(size 0.4572 0.4572)
			(layers "F.Cu" "F.Mask" "F.Paste")
			(net "GND")
		)
		(pad "AB35" smd circle
			(at 9.500108 -2.84988)
			(size 0.4572 0.4572)
			(layers "F.Cu" "F.Mask" "F.Paste")
			(net "Net_532")
		)
		(pad "AB36" smd circle
			(at 10.450068 -2.84988)
			(size 0.4572 0.4572)
			(layers "F.Cu" "F.Mask" "F.Paste")
			(net "GND")
		)
		(pad "AB37" smd circle
			(at 11.400028 -2.84988)
			(size 0.4572 0.4572)
			(layers "F.Cu" "F.Mask" "F.Paste")
			(net "GND")
		)
		(pad "AB38" smd circle
			(at 12.349988 -2.84988)
			(size 0.4572 0.4572)
			(layers "F.Cu" "F.Mask" "F.Paste")
			(net "GND")
		)
		(pad "AB39" smd circle
			(at 13.299948 -2.84988)
			(size 0.4572 0.4572)
			(layers "F.Cu" "F.Mask" "F.Paste")
			(net "GND")
		)
		(pad "AB40" smd circle
			(at 14.249908 -2.84988)
			(size 0.4572 0.4572)
			(layers "F.Cu" "F.Mask" "F.Paste")
			(net "GND")
		)
		(pad "AB41" smd circle
			(at 15.200122 -2.84988)
			(size 0.4572 0.4572)
			(layers "F.Cu" "F.Mask" "F.Paste")
			(net "Net_1566")
		)
		(pad "AB42" smd circle
			(at 16.150082 -2.84988)
			(size 0.4572 0.4572)
			(layers "F.Cu" "F.Mask" "F.Paste")
			(net "Net_1551")
		)
		(pad "AB43" smd circle
			(at 17.100042 -2.84988)
			(size 0.4572 0.4572)
			(layers "F.Cu" "F.Mask" "F.Paste")
			(net "GND")
		)
		(pad "AB44" smd circle
			(at 18.050002 -2.84988)
			(size 0.4572 0.4572)
			(layers "F.Cu" "F.Mask" "F.Paste")
			(net "GND")
		)
		(pad "AB45" smd circle
			(at 18.999962 -2.84988)
			(size 0.4572 0.4572)
			(layers "F.Cu" "F.Mask" "F.Paste")
			(net "GND")
		)
		(pad "AB46" smd circle
			(at 19.949922 -2.84988)
			(size 0.4572 0.4572)
			(layers "F.Cu" "F.Mask" "F.Paste")
			(net "GND")
		)
		(pad "AB47" smd circle
			(at 20.899882 -2.84988)
			(size 0.4572 0.4572)
			(layers "F.Cu" "F.Mask" "F.Paste")
			(net "GND")
		)
		(pad "AB48" smd circle
			(at 21.850096 -2.84988)
			(size 0.4572 0.4572)
			(layers "F.Cu" "F.Mask" "F.Paste")
			(net "Net_1405")
		)
		(pad "AB49" smd circle
			(at 22.800056 -2.84988)
			(size 0.4572 0.4572)
			(layers "F.Cu" "F.Mask" "F.Paste")
			(net "Net_1511")
		)
		(pad "AC1" smd circle
			(at -22.800056 -1.89992)
			(size 0.4572 0.4572)
			(layers "F.Cu" "F.Mask" "F.Paste")
			(net "CLK_100M_DB2000QL_PEX3_S1_R_DN")
		)
		(pad "AC2" smd circle
			(at -21.850096 -1.89992)
			(size 0.4572 0.4572)
			(layers "F.Cu" "F.Mask" "F.Paste")
			(net "CLK_100M_DB2000QL_PEX3_S1_R_DP")
		)
		(pad "AC3" smd circle
			(at -20.899882 -1.89992)
			(size 0.4572 0.4572)
			(layers "F.Cu" "F.Mask" "F.Paste")
			(net "GND")
		)
		(pad "AC4" smd circle
			(at -19.949922 -1.89992)
			(size 0.4572 0.4572)
			(layers "F.Cu" "F.Mask" "F.Paste")
			(net "GND")
		)
		(pad "AC5" smd circle
			(at -18.999962 -1.89992)
			(size 0.4572 0.4572)
			(layers "F.Cu" "F.Mask" "F.Paste")
			(net "GND")
		)
		(pad "AC6" smd circle
			(at -18.050002 -1.89992)
			(size 0.4572 0.4572)
			(layers "F.Cu" "F.Mask" "F.Paste")
			(net "GND")
		)
		(pad "AC7" smd circle
			(at -17.100042 -1.89992)
			(size 0.4572 0.4572)
			(layers "F.Cu" "F.Mask" "F.Paste")
			(net "Net_5488")
		)
		(pad "AC8" smd circle
			(at -16.150082 -1.89992)
			(size 0.4572 0.4572)
			(layers "F.Cu" "F.Mask" "F.Paste")
			(net "Net_5490")
		)
		(pad "AC9" smd circle
			(at -15.200122 -1.89992)
			(size 0.4572 0.4572)
			(layers "F.Cu" "F.Mask" "F.Paste")
			(net "GND")
		)
		(pad "AC10" smd circle
			(at -14.249908 -1.89992)
			(size 0.4572 0.4572)
			(layers "F.Cu" "F.Mask" "F.Paste")
			(net "P1V8_VDDA_PEX3")
		)
		(pad "AC11" smd circle
			(at -13.299948 -1.89992)
			(size 0.4572 0.4572)
			(layers "F.Cu" "F.Mask" "F.Paste")
			(net "GND")
		)
		(pad "AC12" smd circle
			(at -12.349988 -1.89992)
			(size 0.4572 0.4572)
			(layers "F.Cu" "F.Mask" "F.Paste")
			(net "GND")
		)
		(pad "AC13" smd circle
			(at -11.400028 -1.89992)
			(size 0.4572 0.4572)
			(layers "F.Cu" "F.Mask" "F.Paste")
			(net "SYSPLL_VDDA18_PEX3")
		)
		(pad "AC14" smd circle
			(at -10.450068 -1.89992)
			(size 0.4572 0.4572)
			(layers "F.Cu" "F.Mask" "F.Paste")
			(net "GND")
		)
		(pad "AC15" smd circle
			(at -9.500108 -1.89992)
			(size 0.4572 0.4572)
			(layers "F.Cu" "F.Mask" "F.Paste")
			(net "P0V8_PEX3")
		)
		(pad "AC16" smd circle
			(at -8.549894 -1.89992)
			(size 0.4572 0.4572)
			(layers "F.Cu" "F.Mask" "F.Paste")
			(net "GND")
		)
		(pad "AC17" smd circle
			(at -7.599934 -1.89992)
			(size 0.4572 0.4572)
			(layers "F.Cu" "F.Mask" "F.Paste")
			(net "P0V8_PEX3")
		)
		(pad "AC18" smd circle
			(at -6.649974 -1.89992)
			(size 0.4572 0.4572)
			(layers "F.Cu" "F.Mask" "F.Paste")
			(net "GND")
		)
		(pad "AC19" smd circle
			(at -5.700014 -1.89992)
			(size 0.4572 0.4572)
			(layers "F.Cu" "F.Mask" "F.Paste")
			(net "P0V8_PEX3")
		)
		(pad "AC20" smd circle
			(at -4.750054 -1.89992)
			(size 0.4572 0.4572)
			(layers "F.Cu" "F.Mask" "F.Paste")
			(net "GND")
		)
		(pad "AC21" smd circle
			(at -3.800094 -1.89992)
			(size 0.4572 0.4572)
			(layers "F.Cu" "F.Mask" "F.Paste")
			(net "P0V8_PEX3")
		)
		(pad "AC22" smd circle
			(at -2.84988 -1.89992)
			(size 0.4572 0.4572)
			(layers "F.Cu" "F.Mask" "F.Paste")
			(net "GND")
		)
		(pad "AC23" smd circle
			(at -1.89992 -1.89992)
			(size 0.4572 0.4572)
			(layers "F.Cu" "F.Mask" "F.Paste")
			(net "P0V8_PEX3")
		)
		(pad "AC24" smd circle
			(at -0.94996 -1.89992)
			(size 0.4572 0.4572)
			(layers "F.Cu" "F.Mask" "F.Paste")
			(net "GND")
		)
		(pad "AC25" smd circle
			(at 0 -1.89992)
			(size 0.4572 0.4572)
			(layers "F.Cu" "F.Mask" "F.Paste")
			(net "P0V8_PEX3")
		)
		(pad "AC26" smd circle
			(at 0.94996 -1.89992)
			(size 0.4572 0.4572)
			(layers "F.Cu" "F.Mask" "F.Paste")
			(net "GND")
		)
		(pad "AC27" smd circle
			(at 1.89992 -1.89992)
			(size 0.4572 0.4572)
			(layers "F.Cu" "F.Mask" "F.Paste")
			(net "P0V8_PEX3")
		)
		(pad "AC28" smd circle
			(at 2.84988 -1.89992)
			(size 0.4572 0.4572)
			(layers "F.Cu" "F.Mask" "F.Paste")
			(net "GND")
		)
		(pad "AC29" smd circle
			(at 3.800094 -1.89992)
			(size 0.4572 0.4572)
			(layers "F.Cu" "F.Mask" "F.Paste")
			(net "P0V8_PEX3")
		)
		(pad "AC30" smd circle
			(at 4.750054 -1.89992)
			(size 0.4572 0.4572)
			(layers "F.Cu" "F.Mask" "F.Paste")
			(net "GND")
		)
		(pad "AC31" smd circle
			(at 5.700014 -1.89992)
			(size 0.4572 0.4572)
			(layers "F.Cu" "F.Mask" "F.Paste")
			(net "P0V8_PEX3")
		)
		(pad "AC32" smd circle
			(at 6.649974 -1.89992)
			(size 0.4572 0.4572)
			(layers "F.Cu" "F.Mask" "F.Paste")
			(net "GND")
		)
		(pad "AC33" smd circle
			(at 7.599934 -1.89992)
			(size 0.4572 0.4572)
			(layers "F.Cu" "F.Mask" "F.Paste")
			(net "P0V8_PEX3")
		)
		(pad "AC34" smd circle
			(at 8.549894 -1.89992)
			(size 0.4572 0.4572)
			(layers "F.Cu" "F.Mask" "F.Paste")
			(net "GND")
		)
		(pad "AC35" smd circle
			(at 9.500108 -1.89992)
			(size 0.4572 0.4572)
			(layers "F.Cu" "F.Mask" "F.Paste")
			(net "GND")
		)
		(pad "AC36" smd circle
			(at 10.450068 -1.89992)
			(size 0.4572 0.4572)
			(layers "F.Cu" "F.Mask" "F.Paste")
			(net "P1V25_PEX3")
		)
		(pad "AC37" smd circle
			(at 11.400028 -1.89992)
			(size 0.4572 0.4572)
			(layers "F.Cu" "F.Mask" "F.Paste")
			(net "GND")
		)
		(pad "AC38" smd circle
			(at 12.349988 -1.89992)
			(size 0.4572 0.4572)
			(layers "F.Cu" "F.Mask" "F.Paste")
			(net "P1V25_SERDES_VDDPLL_PEX3")
		)
		(pad "AC39" smd circle
			(at 13.299948 -1.89992)
			(size 0.4572 0.4572)
			(layers "F.Cu" "F.Mask" "F.Paste")
			(net "GND")
		)
		(pad "AC40" smd circle
			(at 14.249908 -1.89992)
			(size 0.4572 0.4572)
			(layers "F.Cu" "F.Mask" "F.Paste")
			(net "GND")
		)
		(pad "AC41" smd circle
			(at 15.200122 -1.89992)
			(size 0.4572 0.4572)
			(layers "F.Cu" "F.Mask" "F.Paste")
			(net "GND")
		)
		(pad "AC42" smd circle
			(at 16.150082 -1.89992)
			(size 0.4572 0.4572)
			(layers "F.Cu" "F.Mask" "F.Paste")
			(net "GND")
		)
		(pad "AC43" smd circle
			(at 17.100042 -1.89992)
			(size 0.4572 0.4572)
			(layers "F.Cu" "F.Mask" "F.Paste")
			(net "Net_1527")
		)
		(pad "AC44" smd circle
			(at 18.050002 -1.89992)
			(size 0.4572 0.4572)
			(layers "F.Cu" "F.Mask" "F.Paste")
			(net "Net_1514")
		)
		(pad "AC45" smd circle
			(at 18.999962 -1.89992)
			(size 0.4572 0.4572)
			(layers "F.Cu" "F.Mask" "F.Paste")
			(net "GND")
		)
		(pad "AC46" smd circle
			(at 19.949922 -1.89992)
			(size 0.4572 0.4572)
			(layers "F.Cu" "F.Mask" "F.Paste")
			(net "Net_1456")
		)
		(pad "AC47" smd circle
			(at 20.899882 -1.89992)
			(size 0.4572 0.4572)
			(layers "F.Cu" "F.Mask" "F.Paste")
			(net "Net_1496")
		)
		(pad "AC48" smd circle
			(at 21.850096 -1.89992)
			(size 0.4572 0.4572)
			(layers "F.Cu" "F.Mask" "F.Paste")
			(net "GND")
		)
		(pad "AC49" smd circle
			(at 22.800056 -1.89992)
			(size 0.4572 0.4572)
			(layers "F.Cu" "F.Mask" "F.Paste")
			(net "GND")
		)
		(pad "AD1" smd circle
			(at -22.800056 -0.94996)
			(size 0.4572 0.4572)
			(layers "F.Cu" "F.Mask" "F.Paste")
			(net "GND")
		)
		(pad "AD2" smd circle
			(at -21.850096 -0.94996)
			(size 0.4572 0.4572)
			(layers "F.Cu" "F.Mask" "F.Paste")
			(net "GND")
		)
		(pad "AD3" smd circle
			(at -20.899882 -0.94996)
			(size 0.4572 0.4572)
			(layers "F.Cu" "F.Mask" "F.Paste")
			(net "GND")
		)
		(pad "AD4" smd circle
			(at -19.949922 -0.94996)
			(size 0.4572 0.4572)
			(layers "F.Cu" "F.Mask" "F.Paste")
			(net "Net_381")
		)
		(pad "AD5" smd circle
			(at -18.999962 -0.94996)
			(size 0.4572 0.4572)
			(layers "F.Cu" "F.Mask" "F.Paste")
			(net "Net_388")
		)
		(pad "AD6" smd circle
			(at -18.050002 -0.94996)
			(size 0.4572 0.4572)
			(layers "F.Cu" "F.Mask" "F.Paste")
			(net "GND")
		)
		(pad "AD7" smd circle
			(at -17.100042 -0.94996)
			(size 0.4572 0.4572)
			(layers "F.Cu" "F.Mask" "F.Paste")
			(net "Net_5487")
		)
		(pad "AD8" smd circle
			(at -16.150082 -0.94996)
			(size 0.4572 0.4572)
			(layers "F.Cu" "F.Mask" "F.Paste")
			(net "Net_5489")
		)
		(pad "AD9" smd circle
			(at -15.200122 -0.94996)
			(size 0.4572 0.4572)
			(layers "F.Cu" "F.Mask" "F.Paste")
			(net "GND")
		)
		(pad "AD10" smd circle
			(at -14.249908 -0.94996)
			(size 0.4572 0.4572)
			(layers "F.Cu" "F.Mask" "F.Paste")
			(net "GND")
		)
		(pad "AD11" smd circle
			(at -13.299948 -0.94996)
			(size 0.4572 0.4572)
			(layers "F.Cu" "F.Mask" "F.Paste")
			(net "GND")
		)
		(pad "AD12" smd circle
			(at -12.349988 -0.94996)
			(size 0.4572 0.4572)
			(layers "F.Cu" "F.Mask" "F.Paste")
			(net "PCEPLL2_VDDA18_PEX3")
		)
		(pad "AD13" smd circle
			(at -11.400028 -0.94996)
			(size 0.4572 0.4572)
			(layers "F.Cu" "F.Mask" "F.Paste")
			(net "GND")
		)
		(pad "AD14" smd circle
			(at -10.450068 -0.94996)
			(size 0.4572 0.4572)
			(layers "F.Cu" "F.Mask" "F.Paste")
			(net "P0V8_PEX3")
		)
		(pad "AD15" smd circle
			(at -9.500108 -0.94996)
			(size 0.4572 0.4572)
			(layers "F.Cu" "F.Mask" "F.Paste")
			(net "GND")
		)
		(pad "AD16" smd circle
			(at -8.549894 -0.94996)
			(size 0.4572 0.4572)
			(layers "F.Cu" "F.Mask" "F.Paste")
			(net "P0V8_PEX3")
		)
		(pad "AD17" smd circle
			(at -7.599934 -0.94996)
			(size 0.4572 0.4572)
			(layers "F.Cu" "F.Mask" "F.Paste")
			(net "GND")
		)
		(pad "AD18" smd circle
			(at -6.649974 -0.94996)
			(size 0.4572 0.4572)
			(layers "F.Cu" "F.Mask" "F.Paste")
			(net "P0V8_PEX3")
		)
		(pad "AD19" smd circle
			(at -5.700014 -0.94996)
			(size 0.4572 0.4572)
			(layers "F.Cu" "F.Mask" "F.Paste")
			(net "GND")
		)
		(pad "AD20" smd circle
			(at -4.750054 -0.94996)
			(size 0.4572 0.4572)
			(layers "F.Cu" "F.Mask" "F.Paste")
			(net "P0V8_PEX3")
		)
		(pad "AD21" smd circle
			(at -3.800094 -0.94996)
			(size 0.4572 0.4572)
			(layers "F.Cu" "F.Mask" "F.Paste")
			(net "GND")
		)
		(pad "AD22" smd circle
			(at -2.84988 -0.94996)
			(size 0.4572 0.4572)
			(layers "F.Cu" "F.Mask" "F.Paste")
			(net "P0V8_PEX3")
		)
		(pad "AD23" smd circle
			(at -1.89992 -0.94996)
			(size 0.4572 0.4572)
			(layers "F.Cu" "F.Mask" "F.Paste")
			(net "GND")
		)
		(pad "AD24" smd circle
			(at -0.94996 -0.94996)
			(size 0.4572 0.4572)
			(layers "F.Cu" "F.Mask" "F.Paste")
			(net "P0V8_PEX3")
		)
		(pad "AD25" smd circle
			(at 0 -0.94996)
			(size 0.4572 0.4572)
			(layers "F.Cu" "F.Mask" "F.Paste")
			(net "GND")
		)
		(pad "AD26" smd circle
			(at 0.94996 -0.94996)
			(size 0.4572 0.4572)
			(layers "F.Cu" "F.Mask" "F.Paste")
			(net "P0V8_PEX3")
		)
		(pad "AD27" smd circle
			(at 1.89992 -0.94996)
			(size 0.4572 0.4572)
			(layers "F.Cu" "F.Mask" "F.Paste")
			(net "GND")
		)
		(pad "AD28" smd circle
			(at 2.84988 -0.94996)
			(size 0.4572 0.4572)
			(layers "F.Cu" "F.Mask" "F.Paste")
			(net "P0V8_PEX3")
		)
		(pad "AD29" smd circle
			(at 3.800094 -0.94996)
			(size 0.4572 0.4572)
			(layers "F.Cu" "F.Mask" "F.Paste")
			(net "GND")
		)
		(pad "AD30" smd circle
			(at 4.750054 -0.94996)
			(size 0.4572 0.4572)
			(layers "F.Cu" "F.Mask" "F.Paste")
			(net "P0V8_PEX3")
		)
		(pad "AD31" smd circle
			(at 5.700014 -0.94996)
			(size 0.4572 0.4572)
			(layers "F.Cu" "F.Mask" "F.Paste")
			(net "GND")
		)
		(pad "AD32" smd circle
			(at 6.649974 -0.94996)
			(size 0.4572 0.4572)
			(layers "F.Cu" "F.Mask" "F.Paste")
			(net "P0V8_SERDES_VDDA_PEX3")
		)
		(pad "AD33" smd circle
			(at 7.599934 -0.94996)
			(size 0.4572 0.4572)
			(layers "F.Cu" "F.Mask" "F.Paste")
			(net "P0V8_SERDES_VDDA_PEX3")
		)
		(pad "AD34" smd circle
			(at 8.549894 -0.94996)
			(size 0.4572 0.4572)
			(layers "F.Cu" "F.Mask" "F.Paste")
			(net "P0V8_SERDES_VDDA_PEX3")
		)
		(pad "AD35" smd circle
			(at 9.500108 -0.94996)
			(size 0.4572 0.4572)
			(layers "F.Cu" "F.Mask" "F.Paste")
			(net "GND")
		)
		(pad "AD36" smd circle
			(at 10.450068 -0.94996)
			(size 0.4572 0.4572)
			(layers "F.Cu" "F.Mask" "F.Paste")
			(net "P1V25_PEX3")
		)
		(pad "AD37" smd circle
			(at 11.400028 -0.94996)
			(size 0.4572 0.4572)
			(layers "F.Cu" "F.Mask" "F.Paste")
			(net "GND")
		)
		(pad "AD38" smd circle
			(at 12.349988 -0.94996)
			(size 0.4572 0.4572)
			(layers "F.Cu" "F.Mask" "F.Paste")
			(net "P1V25_SERDES_VDDPLL_PEX3")
		)
		(pad "AD39" smd circle
			(at 13.299948 -0.94996)
			(size 0.4572 0.4572)
			(layers "F.Cu" "F.Mask" "F.Paste")
			(net "GND")
		)
	)
)
